# BASEBOARD_FAB2 (Tioga Pass) — schematic netlist excerpt (pin names and nets, part order shuffled) for the footprints in the layout excerpt that follows; sources: Cadence DE-HDL packaged netlist, KiCad conversion of Wiwynn_Tioga_Pass_MB.brd

C25W50  CAP  4.7UF 6.3V 10% X6S  pkg 0603  page 149 : A = P3V3_STBY ; B = GND
R7M1  RES  665 1.0% CHIP  pkg 0402  page 99 : A = PVPP_KLM ; B = SMB_DDR_KLM_VPP_SCL_R
C2T16  CAP_A  0.1UF 16V 10% X7R  pkg 0402V  page 185 : A = P3V3 ; B = GND

(kicad_pcb
	(version 20260206)
	(generator "pcbnew")
	(generator_version "10.0")
	(general
		(thickness 1.6)
		(legacy_teardrops no)
	)
	(paper "A4")
	(title_block
		(title "Wiwynn_Tioga_Pass_MB.brd")
		(comment 1 "Tioga Pass / footprints 4259-4261 of 4770")
	)
	(layers
		(0 "F.Cu" signal "TOP")
		(4 "In1.Cu" signal "L2GND")
		(6 "In2.Cu" signal "L3")
		(8 "In3.Cu" signal "L4GND")
		(10 "In4.Cu" signal "L5")
		(12 "In5.Cu" signal "L6GND")
		(14 "In6.Cu" signal "L7VCC")
		(16 "In7.Cu" signal "L8VCC")
		(18 "In8.Cu" signal "L9GND")
		(20 "In9.Cu" signal "L10")
		(22 "In10.Cu" signal "L11GND")
		(24 "In11.Cu" signal "L12")
		(26 "In12.Cu" signal "L13GND")
		(2 "B.Cu" signal "BOTTOM")
		(9 "F.Adhes" user "F.Adhesive")
		(11 "B.Adhes" user "B.Adhesive")
		(13 "F.Paste" user "Package Geometry/Pastemask Top")
		(15 "B.Paste" user "Package Geometry/Pastemask Bottom")
		(5 "F.SilkS" user "Ref Des/Silkscreen Top")
		(7 "B.SilkS" user "Ref Des/Silkscreen Bottom")
		(1 "F.Mask" user "Board Geometry/Soldermask Top")
		(3 "B.Mask" user "Board Geometry/Soldermask Bottom")
		(17 "Dwgs.User" user "User.Drawings")
		(19 "Cmts.User" user "User.Comments")
		(21 "Eco1.User" user "User.Eco1")
		(23 "Eco2.User" user "User.Eco2")
		(25 "Edge.Cuts" user "Board Geometry/Outline")
		(27 "Margin" user)
		(31 "F.CrtYd" user "Package Geometry/Place Bound Top")
		(29 "B.CrtYd" user "Package Geometry/Place Bound Bottom")
		(35 "F.Fab" user "Ref Des/Assembly Top")
		(33 "B.Fab" user "Ref Des/Assembly Bottom")
	)
	(footprint ""
		(layer "B.Cu")
		(at 409.917646 -22.996652 -90)
		(property "Reference" "C25W50"
			(at -0.97536 0.76708 0)
			(unlocked yes)
			(layer "B.SilkS")
			(effects
				(font
					(size 0.4064 0.254)
					(thickness 0.1524)
				)
				(justify mirror)
			)
		)
		(property "Value" ""
			(at 0 0 90)
			(layer "B.Fab")
			(effects
				(font
					(size 1.27 1.27)
				)
				(justify mirror)
			)
		)
		(duplicate_pad_numbers_are_jumpers no)
		(fp_poly
			(pts
				(xy 0.4953 -0.2032) (xy -0.4953 -0.2032) (xy -0.4953 1.6002) (xy 0.4953 1.6002)
			)
			(stroke
				(width 0)
				(type default)
			)
			(fill no)
			(layer "B.CrtYd")
		)
		(fp_line
			(start -0.4953 1.6002)
			(end 0.4953 1.6002)
			(stroke
				(width 0.1)
				(type default)
			)
			(layer "B.Fab")
		)
		(fp_line
			(start 0.4953 1.6002)
			(end 0.4953 -0.2032)
			(stroke
				(width 0.1)
				(type default)
			)
			(layer "B.Fab")
		)
		(fp_line
			(start -0.4953 -0.2032)
			(end -0.4953 1.6002)
			(stroke
				(width 0.1)
				(type default)
			)
			(layer "B.Fab")
		)
		(fp_line
			(start 0.4953 -0.2032)
			(end -0.4953 -0.2032)
			(stroke
				(width 0.1)
				(type default)
			)
			(layer "B.Fab")
		)
		(pad "1" smd rect
			(at 0 0 90)
			(size 0.762 0.889)
			(layers "B.Cu" "B.Mask" "B.Paste")
			(net "P3V3_STBY")
		)
		(pad "2" smd rect
			(at 0 1.397 90)
			(size 0.762 0.889)
			(layers "B.Cu" "B.Mask" "B.Paste")
			(net "GND")
		)
		(zone
			(layer "B.Cu")
			(hatch none 0.5)
			(connect_pads
				(clearance 0)
			)
			(min_thickness 0.25)
			(keepout
				(tracks not_allowed)
				(vias allowed)
				(pads allowed)
				(copperpour not_allowed)
				(footprints allowed)
			)
			(placement
				(enabled no)
				(sheetname "")
			)
			(fill
				(thermal_gap 0.5)
				(thermal_bridge_width 0.5)
				(island_removal_mode 0)
			)
			(polygon
				(pts
					(xy 409.473146 -22.615652) (xy 409.473146 -23.377652) (xy 408.965146 -23.377652) (xy 408.965146 -22.615652)
				)
			)
		)
	)
	(footprint ""
		(layer "B.Cu")
		(at 160.76422 -123.9647)
		(property "Reference" "R7M1"
			(at 0 0 0)
			(layer "B.SilkS")
			(hide yes)
			(effects
				(font
					(size 1.27 1.27)
				)
				(justify mirror)
			)
		)
		(property "Value" ""
			(at 0 0 0)
			(layer "B.Fab")
			(effects
				(font
					(size 1.27 1.27)
				)
				(justify mirror)
			)
		)
		(duplicate_pad_numbers_are_jumpers no)
		(fp_poly
			(pts
				(xy 0.2794 -0.1016) (xy -0.2794 -0.1016) (xy -0.2794 0.9906) (xy 0.2794 0.9906)
			)
			(stroke
				(width 0)
				(type default)
			)
			(fill no)
			(layer "B.CrtYd")
		)
		(fp_line
			(start -0.2794 -0.1016)
			(end 0.2794 -0.1016)
			(stroke
				(width 0.1)
				(type default)
			)
			(layer "B.Fab")
		)
		(fp_line
			(start -0.2794 0.9906)
			(end -0.2794 -0.1016)
			(stroke
				(width 0.1)
				(type default)
			)
			(layer "B.Fab")
		)
		(fp_line
			(start 0.2794 -0.1016)
			(end 0.2794 0.9906)
			(stroke
				(width 0.1)
				(type default)
			)
			(layer "B.Fab")
		)
		(fp_line
			(start 0.2794 0.9906)
			(end -0.2794 0.9906)
			(stroke
				(width 0.1)
				(type default)
			)
			(layer "B.Fab")
		)
		(pad "1" smd rect
			(at 0 0 180)
			(size 0.508 0.508)
			(layers "B.Cu" "B.Mask" "B.Paste")
			(net "PVPP_KLM")
		)
		(pad "2" smd rect
			(at 0 0.889 180)
			(size 0.508 0.508)
			(layers "B.Cu" "B.Mask" "B.Paste")
			(net "SMB_DDR_KLM_VPP_SCL_R")
		)
		(zone
			(layer "B.Cu")
			(hatch none 0.5)
			(connect_pads
				(clearance 0)
			)
			(min_thickness 0.25)
			(keepout
				(tracks allowed)
				(vias not_allowed)
				(pads allowed)
				(copperpour not_allowed)
				(footprints allowed)
			)
			(placement
				(enabled no)
				(sheetname "")
			)
			(fill
				(thermal_gap 0.5)
				(thermal_bridge_width 0.5)
				(island_removal_mode 0)
			)
			(polygon
				(pts
					(xy 161.01822 -123.7107) (xy 160.51022 -123.7107) (xy 160.51022 -123.3297) (xy 161.01822 -123.3297)
				)
			)
		)
		(zone
			(layer "B.Cu")
			(hatch none 0.5)
			(connect_pads
				(clearance 0)
			)
			(min_thickness 0.25)
			(keepout
				(tracks not_allowed)
				(vias allowed)
				(pads allowed)
				(copperpour not_allowed)
				(footprints allowed)
			)
			(placement
				(enabled no)
				(sheetname "")
			)
			(fill
				(thermal_gap 0.5)
				(thermal_bridge_width 0.5)
				(island_removal_mode 0)
			)
			(polygon
				(pts
					(xy 161.01822 -123.3297) (xy 160.51022 -123.3297) (xy 160.51022 -123.7107) (xy 161.01822 -123.7107)
				)
			)
		)
	)
	(footprint ""
		(layer "B.Cu")
		(at 390.635744 -24.981916 -90)
		(property "Reference" "C2T16"
			(at 0 0 90)
			(layer "B.SilkS")
			(hide yes)
			(effects
				(font
					(size 1.27 1.27)
				)
				(justify mirror)
			)
		)
		(property "Value" ""
			(at 0 0 90)
			(layer "B.Fab")
			(effects
				(font
					(size 1.27 1.27)
				)
				(justify mirror)
			)
		)
		(duplicate_pad_numbers_are_jumpers no)
		(fp_poly
			(pts
				(xy -0.3048 -0.1016) (xy -0.3048 0.9906) (xy 0.3048 0.9906) (xy 0.3048 -0.1016)
			)
			(stroke
				(width 0)
				(type default)
			)
			(fill no)
			(layer "B.CrtYd")
		)
		(fp_line
			(start -0.3048 0.9906)
			(end -0.3048 -0.1016)
			(stroke
				(width 0.1)
				(type default)
			)
			(layer "B.Fab")
		)
		(fp_line
			(start 0.3048 0.9906)
			(end -0.3048 0.9906)
			(stroke
				(width 0.1)
				(type default)
			)
			(layer "B.Fab")
		)
		(fp_line
			(start -0.3048 -0.1016)
			(end 0.3048 -0.1016)
			(stroke
				(width 0.1)
				(type default)
			)
			(layer "B.Fab")
		)
		(fp_line
			(start 0.3048 -0.1016)
			(end 0.3048 0.9906)
			(stroke
				(width 0.1)
				(type default)
			)
			(layer "B.Fab")
		)
		(pad "1" smd rect
			(at 0 0 90)
			(size 0.508 0.508)
			(layers "B.Cu" "B.Mask" "B.Paste")
			(net "P3V3")
		)
		(pad "2" smd rect
			(at 0 0.889 90)
			(size 0.508 0.508)
			(layers "B.Cu" "B.Mask" "B.Paste")
			(net "GND")
		)
		(zone
			(layer "B.Cu")
			(hatch none 0.5)
			(connect_pads
				(clearance 0)
			)
			(min_thickness 0.25)
			(keepout
				(tracks not_allowed)
				(vias allowed)
				(pads allowed)
				(copperpour not_allowed)
				(footprints allowed)
			)
			(placement
				(enabled no)
				(sheetname "")
			)
			(fill
				(thermal_gap 0.5)
				(thermal_bridge_width 0.5)
				(island_removal_mode 0)
			)
			(polygon
				(pts
					(xy 390.000744 -24.727916) (xy 390.000744 -25.235916) (xy 390.381744 -25.235916) (xy 390.381744 -24.727916)
				)
			)
		)
		(zone
			(layer "B.Cu")
			(hatch none 0.5)
			(connect_pads
				(clearance 0)
			)
			(min_thickness 0.25)
			(keepout
				(tracks allowed)
				(vias not_allowed)
				(pads allowed)
				(copperpour not_allowed)
				(footprints allowed)
			)
			(placement
				(enabled no)
				(sheetname "")
			)
			(fill
				(thermal_gap 0.5)
				(thermal_bridge_width 0.5)
				(island_removal_mode 0)
			)
			(polygon
				(pts
					(xy 390.381744 -24.727916) (xy 390.381744 -25.235916) (xy 390.000744 -25.235916) (xy 390.000744 -24.727916)
				)
			)
		)
	)
)
